(kicad_pcb
	(version 20241229)
	(generator "pcbnew")
	(generator_version "9.0")
	(general
		(thickness 1.6)
		(legacy_teardrops no)
	)
	(paper "A4")
	(title_block
		(title "OCuLink to PCIe adapter")
		(date "2025-06-18")
		(rev "1.0.0")
		(company "Antmicro Ltd")
		(comment 1 "www.antmicro.com")
		(comment 9 "footprints 4-9 of 159")
	)
	(layers
		(0 "F.Cu" signal)
		(4 "In1.Cu" signal)
		(6 "In2.Cu" signal)
		(2 "B.Cu" signal)
		(9 "F.Adhes" user "F.Adhesive")
		(11 "B.Adhes" user "B.Adhesive")
		(13 "F.Paste" user)
		(15 "B.Paste" user)
		(5 "F.SilkS" user "F.Silkscreen")
		(7 "B.SilkS" user "B.Silkscreen")
		(1 "F.Mask" user)
		(3 "B.Mask" user)
		(17 "Dwgs.User" user "User.Drawings")
		(19 "Cmts.User" user "User.Comments")
		(21 "Eco1.User" user "User.Eco1")
		(23 "Eco2.User" user "User.Eco2")
		(25 "Edge.Cuts" user)
		(27 "Margin" user)
		(31 "F.CrtYd" user "F.Courtyard")
		(29 "B.CrtYd" user "B.Courtyard")
		(35 "F.Fab" user)
		(33 "B.Fab" user)
	)
	(footprint "antmicro-footprints:R_0402_1005Metric"
		(layer "F.Cu")
		(at 125.5 51.98 -90)
		(descr "Resistor SMD 0402")
		(tags "resistor SMD 0402")
		(property "Reference" "R52"
			(at -1.122484 -0.772697 90)
			(layer "F.SilkS")
			(effects
				(font
					(size 0.7 0.7)
					(thickness 0.15)
				)
				(justify right top)
			)
		)
		(property "Value" "R_0R_0402"
			(at -1.011843 1.772046 90)
			(layer "F.Fab")
			(effects
				(font
					(size 0.7 0.7)
					(thickness 0.15)
				)
				(justify right top)
			)
		)
		(property "Datasheet" "https://industrial.panasonic.com/cdbs/www-data/pdf/RDA0000/AOA0000C301.pdf"
			(at 0 0 90)
			(layer "F.Fab")
			(hide yes)
			(effects
				(font
					(size 1.27 1.27)
					(thickness 0.15)
				)
			)
		)
		(property "Description" "SMD Chip Resistor, Jumper, 0 ohm, 100 mW, 0402 [1005 Metric], Thick Film, General Purpose"
			(at 0 0 90)
			(layer "F.Fab")
			(hide yes)
			(effects
				(font
					(size 1.27 1.27)
					(thickness 0.15)
				)
			)
		)
		(property "MPN" "ERJ2GE0R00X"
			(at 0 0 270)
			(unlocked yes)
			(layer "F.Fab")
			(hide yes)
			(effects
				(font
					(size 1 1)
					(thickness 0.15)
				)
			)
		)
		(property "Manufacturer" "Panasonic"
			(at 0 0 270)
			(unlocked yes)
			(layer "F.Fab")
			(hide yes)
			(effects
				(font
					(size 1 1)
					(thickness 0.15)
				)
			)
		)
		(property "License" "Apache-2.0"
			(at 0 0 270)
			(unlocked yes)
			(layer "F.Fab")
			(hide yes)
			(effects
				(font
					(size 1 1)
					(thickness 0.15)
				)
			)
		)
		(property "Author" "Antmicro"
			(at 0 0 270)
			(unlocked yes)
			(layer "F.Fab")
			(hide yes)
			(effects
				(font
					(size 1 1)
					(thickness 0.15)
				)
			)
		)
		(property "Val" "0R"
			(at 0 0 270)
			(unlocked yes)
			(layer "F.Fab")
			(hide yes)
			(effects
				(font
					(size 1 1)
					(thickness 0.15)
				)
			)
		)
		(property "Tolerance" ""
			(at 0 0 270)
			(unlocked yes)
			(layer "F.Fab")
			(hide yes)
			(effects
				(font
					(size 1 1)
					(thickness 0.15)
				)
			)
		)
		(property "Current" "1A"
			(at 0 0 270)
			(unlocked yes)
			(layer "F.Fab")
			(hide yes)
			(effects
				(font
					(size 1 1)
					(thickness 0.15)
				)
			)
		)
		(sheetname "/OCuLink/")
		(sheetfile "oculink.kicad_sch")
		(attr smd)
		(fp_rect
			(start -0.925 -0.47)
			(end 0.925 0.47)
			(stroke
				(width 0.05)
				(type default)
			)
			(fill no)
			(layer "F.CrtYd")
		)
		(fp_rect
			(start -0.5 -0.25)
			(end 0.5 0.25)
			(stroke
				(width 0.15)
				(type solid)
			)
			(fill no)
			(layer "F.Fab")
		)
		(fp_text user "Author: Antmicro"
			(at -0.95 4.169 90)
			(layer "F.Fab")
			(effects
				(font
					(size 0.7 0.7)
					(thickness 0.15)
				)
				(justify right top)
			)
		)
		(fp_text user "License: Apache-2.0"
			(at -0.949999 5.169 90)
			(layer "F.Fab")
			(effects
				(font
					(size 0.7 0.7)
					(thickness 0.15)
				)
				(justify right top)
			)
		)
		(fp_text user "${REFERENCE}"
			(at -0.95 3.168 90)
			(layer "F.Fab")
			(effects
				(font
					(size 0.7 0.7)
					(thickness 0.15)
				)
				(justify right top)
			)
		)
		(pad "1" smd roundrect
			(at -0.48 0 270)
			(size 0.59 0.64)
			(layers "F.Cu" "F.Mask" "F.Paste")
			(roundrect_rratio 0.25)
			(net 184 "/OCuLink/~{WAKEC}")
			(pintype "passive")
		)
		(pad "2" smd roundrect
			(at 0.48 0 270)
			(size 0.59 0.64)
			(layers "F.Cu" "F.Mask" "F.Paste")
			(roundrect_rratio 0.25)
			(net 93 "/OCuLink/~{WAKE}")
			(pintype "passive")
		)
	)
	(footprint "antmicro-footprints:C_0402_1005Metric"
		(layer "F.Cu")
		(at 124.882999 149.054999 90)
		(descr "Capacitor SMD 0402")
		(tags "capacitor SMD 0402")
		(property "Reference" "C12"
			(at 1.054999 0.317001 270)
			(layer "F.SilkS")
			(effects
				(font
					(size 0.7 0.7)
					(thickness 0.15)
				)
				(justify left bottom)
			)
		)
		(property "Value" "C_100n_0402"
			(at -1.022927 2.155213 90)
			(layer "F.Fab")
			(effects
				(font
					(size 0.7 0.7)
					(thickness 0.15)
				)
				(justify left bottom)
			)
		)
		(property "Datasheet" "https://www.murata.com/products/productdetail?partno=GRM155R61H104KE14%23"
			(at 0 0 90)
			(layer "F.Fab")
			(hide yes)
			(effects
				(font
					(size 1.27 1.27)
					(thickness 0.15)
				)
			)
		)
		(property "Description" "SMD Multilayer Ceramic Capacitor, 0.1 µF, 50 V, 0402 [1005 Metric], ± 10%, X5R, GRM Series"
			(at 0 0 90)
			(layer "F.Fab")
			(hide yes)
			(effects
				(font
					(size 1.27 1.27)
					(thickness 0.15)
				)
			)
		)
		(property "MPN" "GRM155R61H104KE14D"
			(at 0 0 90)
			(unlocked yes)
			(layer "F.Fab")
			(hide yes)
			(effects
				(font
					(size 1 1)
					(thickness 0.15)
				)
			)
		)
		(property "Manufacturer" "Murata"
			(at 0 0 90)
			(unlocked yes)
			(layer "F.Fab")
			(hide yes)
			(effects
				(font
					(size 1 1)
					(thickness 0.15)
				)
			)
		)
		(property "License" "Apache-2.0"
			(at 0 0 90)
			(unlocked yes)
			(layer "F.Fab")
			(hide yes)
			(effects
				(font
					(size 1 1)
					(thickness 0.15)
				)
			)
		)
		(property "Author" "Antmicro"
			(at 0 0 90)
			(unlocked yes)
			(layer "F.Fab")
			(hide yes)
			(effects
				(font
					(size 1 1)
					(thickness 0.15)
				)
			)
		)
		(property "Val" "100n"
			(at 0 0 90)
			(unlocked yes)
			(layer "F.Fab")
			(hide yes)
			(effects
				(font
					(size 1 1)
					(thickness 0.15)
				)
			)
		)
		(property "Voltage" "50V"
			(at 0 0 90)
			(unlocked yes)
			(layer "F.Fab")
			(hide yes)
			(effects
				(font
					(size 1 1)
					(thickness 0.15)
				)
			)
		)
		(property "Dielectric" "X5R"
			(at 0 0 90)
			(unlocked yes)
			(layer "F.Fab")
			(hide yes)
			(effects
				(font
					(size 1 1)
					(thickness 0.15)
				)
			)
		)
		(sheetname "/Power/")
		(sheetfile "power.kicad_sch")
		(attr smd)
		(fp_rect
			(start -0.925 -0.47)
			(end 0.925 0.47)
			(stroke
				(width 0.05)
				(type default)
			)
			(fill no)
			(layer "F.CrtYd")
		)
		(fp_line
			(start 0.504 -0.25)
			(end 0.504 0.248)
			(stroke
				(width 0.15)
				(type solid)
			)
			(layer "F.Fab")
		)
		(fp_line
			(start -0.494 -0.25)
			(end 0.504 -0.25)
			(stroke
				(width 0.15)
				(type solid)
			)
			(layer "F.Fab")
		)
		(fp_line
			(start 0.504 0.248)
			(end -0.494 0.248)
			(stroke
				(width 0.15)
				(type solid)
			)
			(layer "F.Fab")
		)
		(fp_line
			(start -0.494 0.248)
			(end -0.494 -0.25)
			(stroke
				(width 0.15)
				(type solid)
			)
			(layer "F.Fab")
		)
		(fp_text user "${REFERENCE}"
			(at 0 0 90)
			(layer "F.Fab")
			(effects
				(font
					(size 0.7 0.7)
					(thickness 0.15)
				)
				(justify left bottom)
			)
		)
		(fp_text user "License: Apache-2.0"
			(at -0.939 5.799 90)
			(layer "F.Fab")
			(effects
				(font
					(size 0.7 0.7)
					(thickness 0.15)
				)
				(justify left bottom)
			)
		)
		(fp_text user "Author: Antmicro"
			(at -0.939 3.399 90)
			(layer "F.Fab")
			(effects
				(font
					(size 0.7 0.7)
					(thickness 0.15)
				)
				(justify left bottom)
			)
		)
		(pad "1" smd roundrect
			(at -0.48 0 90)
			(size 0.59 0.64)
			(layers "F.Cu" "F.Mask" "F.Paste")
			(roundrect_rratio 0.25)
			(net 66 "GND")
			(pintype "passive")
		)
		(pad "2" smd roundrect
			(at 0.48 0 90)
			(size 0.59 0.64)
			(layers "F.Cu" "F.Mask" "F.Paste")
			(roundrect_rratio 0.25)
			(net 134 "+3V3")
			(pintype "passive")
		)
	)
	(footprint "antmicro-footprints:TP_Pad0.75mm_Drill0.2mm"
		(layer "F.Cu")
		(at 150.8 42.7 180)
		(property "Reference" "TP4"
			(at 2.7 -0.3 180)
			(layer "F.SilkS")
			(effects
				(font
					(size 0.7 0.7)
					(thickness 0.15)
				)
				(justify left bottom)
			)
		)
		(property "Value" "TP_Pad0.75mm_Drill0.2mm"
			(at 0 1.2 180)
			(layer "F.Fab")
			(effects
				(font
					(size 0.7 0.7)
					(thickness 0.15)
				)
				(justify left bottom)
			)
		)
		(property "Description" "SMT test point"
			(at 0 0 180)
			(layer "F.Fab")
			(hide yes)
			(effects
				(font
					(size 1.27 1.27)
					(thickness 0.15)
				)
			)
		)
		(property "MPN" ""
			(at 0 0 180)
			(unlocked yes)
			(layer "F.Fab")
			(hide yes)
			(effects
				(font
					(size 1 1)
					(thickness 0.15)
				)
			)
		)
		(property "Manufacturer" ""
			(at 0 0 180)
			(unlocked yes)
			(layer "F.Fab")
			(hide yes)
			(effects
				(font
					(size 1 1)
					(thickness 0.15)
				)
			)
		)
		(property "Author" "Antmicro"
			(at 0 0 180)
			(unlocked yes)
			(layer "F.Fab")
			(hide yes)
			(effects
				(font
					(size 1 1)
					(thickness 0.15)
				)
			)
		)
		(property "License" "Apache-2.0"
			(at 0 0 180)
			(unlocked yes)
			(layer "F.Fab")
			(hide yes)
			(effects
				(font
					(size 1 1)
					(thickness 0.15)
				)
			)
		)
		(sheetname "/USB-PD/")
		(sheetfile "usb-pd.kicad_sch")
		(attr exclude_from_pos_files exclude_from_bom)
		(fp_circle
			(center 0 0)
			(end 0.475 0)
			(stroke
				(width 0.05)
				(type default)
			)
			(fill no)
			(layer "F.CrtYd")
		)
		(fp_text user "License: Apache-2.0"
			(at -0.4 5.101 180)
			(layer "F.Fab")
			(effects
				(font
					(size 0.7 0.7)
					(thickness 0.15)
				)
				(justify left bottom)
			)
		)
		(fp_text user "${REFERENCE}"
			(at -0.4 2.7 180)
			(layer "F.Fab")
			(effects
				(font
					(size 0.7 0.7)
					(thickness 0.15)
				)
				(justify left bottom)
			)
		)
		(fp_text user "Author: Antmicro"
			(at -0.4 3.901 180)
			(layer "F.Fab")
			(effects
				(font
					(size 0.7 0.7)
					(thickness 0.15)
				)
				(justify left bottom)
			)
		)
		(pad "1" thru_hole circle
			(at 0 0 180)
			(size 0.75 0.75)
			(drill 0.2)
			(layers "*.Cu" "*.Mask")
			(remove_unused_layers no)
			(net 113 "VBUS")
			(pinfunction "1")
			(pintype "passive")
		)
	)
	(footprint "antmicro-footprints:TP_Pad0.75mm_Drill0.2mm"
		(layer "F.Cu")
		(at 155.75 148 -90)
		(property "Reference" "TP1"
			(at 0.5 -0.6 0)
			(layer "F.SilkS")
			(effects
				(font
					(size 0.7 0.7)
					(thickness 0.15)
				)
				(justify left bottom)
			)
		)
		(property "Value" "TP_Pad0.75mm_Drill0.2mm"
			(at 0 1.2 270)
			(layer "F.Fab")
			(effects
				(font
					(size 0.7 0.7)
					(thickness 0.15)
				)
				(justify left bottom)
			)
		)
		(property "Description" "SMT test point"
			(at 0 0 270)
			(layer "F.Fab")
			(hide yes)
			(effects
				(font
					(size 1.27 1.27)
					(thickness 0.15)
				)
			)
		)
		(property "MPN" ""
			(at 0 0 270)
			(unlocked yes)
			(layer "F.Fab")
			(hide yes)
			(effects
				(font
					(size 1 1)
					(thickness 0.15)
				)
			)
		)
		(property "Manufacturer" ""
			(at 0 0 270)
			(unlocked yes)
			(layer "F.Fab")
			(hide yes)
			(effects
				(font
					(size 1 1)
					(thickness 0.15)
				)
			)
		)
		(property "Author" "Antmicro"
			(at 0 0 270)
			(unlocked yes)
			(layer "F.Fab")
			(hide yes)
			(effects
				(font
					(size 1 1)
					(thickness 0.15)
				)
			)
		)
		(property "License" "Apache-2.0"
			(at 0 0 270)
			(unlocked yes)
			(layer "F.Fab")
			(hide yes)
			(effects
				(font
					(size 1 1)
					(thickness 0.15)
				)
			)
		)
		(sheetname "/Power/")
		(sheetfile "power.kicad_sch")
		(attr exclude_from_pos_files exclude_from_bom)
		(fp_circle
			(center 0 0)
			(end 0.475 0)
			(stroke
				(width 0.05)
				(type default)
			)
			(fill no)
			(layer "F.CrtYd")
		)
		(fp_text user "Author: Antmicro"
			(at -0.4 3.901 270)
			(layer "F.Fab")
			(effects
				(font
					(size 0.7 0.7)
					(thickness 0.15)
				)
				(justify left bottom)
			)
		)
		(fp_text user "License: Apache-2.0"
			(at -0.4 5.101 270)
			(layer "F.Fab")
			(effects
				(font
					(size 0.7 0.7)
					(thickness 0.15)
				)
				(justify left bottom)
			)
		)
		(fp_text user "${REFERENCE}"
			(at -0.4 2.7 270)
			(layer "F.Fab")
			(effects
				(font
					(size 0.7 0.7)
					(thickness 0.15)
				)
				(justify left bottom)
			)
		)
		(pad "1" thru_hole circle
			(at 0 0 270)
			(size 0.75 0.75)
			(drill 0.2)
			(layers "*.Cu" "*.Mask")
			(remove_unused_layers no)
			(net 172 "/Power/~{PERST}")
			(pinfunction "1")
			(pintype "passive")
		)
	)
	(footprint "antmicro-footprints:TP_Pad0.75mm_Drill0.2mm"
		(layer "F.Cu")
		(at 155.75 154)
		(property "Reference" "TP8"
			(at 0.6 0.5 0)
			(layer "F.SilkS")
			(effects
				(font
					(size 0.7 0.7)
					(thickness 0.15)
				)
				(justify left bottom)
			)
		)
		(property "Value" "TP_Pad0.75mm_Drill0.2mm"
			(at 0 1.2 0)
			(layer "F.Fab")
			(effects
				(font
					(size 0.7 0.7)
					(thickness 0.15)
				)
				(justify left bottom)
			)
		)
		(property "Description" "SMT test point"
			(at 0 0 0)
			(layer "F.Fab")
			(hide yes)
			(effects
				(font
					(size 1.27 1.27)
					(thickness 0.15)
				)
			)
		)
		(property "MPN" ""
			(at 0 0 0)
			(unlocked yes)
			(layer "F.Fab")
			(hide yes)
			(effects
				(font
					(size 1 1)
					(thickness 0.15)
				)
			)
		)
		(property "Manufacturer" ""
			(at 0 0 0)
			(unlocked yes)
			(layer "F.Fab")
			(hide yes)
			(effects
				(font
					(size 1 1)
					(thickness 0.15)
				)
			)
		)
		(property "Author" "Antmicro"
			(at 0 0 0)
			(unlocked yes)
			(layer "F.Fab")
			(hide yes)
			(effects
				(font
					(size 1 1)
					(thickness 0.15)
				)
			)
		)
		(property "License" "Apache-2.0"
			(at 0 0 0)
			(unlocked yes)
			(layer "F.Fab")
			(hide yes)
			(effects
				(font
					(size 1 1)
					(thickness 0.15)
				)
			)
		)
		(sheetname "/Power/")
		(sheetfile "power.kicad_sch")
		(attr exclude_from_pos_files exclude_from_bom)
		(fp_circle
			(center 0 0)
			(end 0.475 0)
			(stroke
				(width 0.05)
				(type default)
			)
			(fill no)
			(layer "F.CrtYd")
		)
		(fp_text user "${REFERENCE}"
			(at -0.4 2.7 0)
			(layer "F.Fab")
			(effects
				(font
					(size 0.7 0.7)
					(thickness 0.15)
				)
				(justify left bottom)
			)
		)
		(fp_text user "License: Apache-2.0"
			(at -0.4 5.101 0)
			(layer "F.Fab")
			(effects
				(font
					(size 0.7 0.7)
					(thickness 0.15)
				)
				(justify left bottom)
			)
		)
		(fp_text user "Author: Antmicro"
			(at -0.4 3.901 0)
			(layer "F.Fab")
			(effects
				(font
					(size 0.7 0.7)
					(thickness 0.15)
				)
				(justify left bottom)
			)
		)
		(pad "1" thru_hole circle
			(at 0 0)
			(size 0.75 0.75)
			(drill 0.2)
			(layers "*.Cu" "*.Mask")
			(remove_unused_layers no)
			(net 66 "GND")
			(pinfunction "1")
			(pintype "passive")
		)
	)
	(footprint "antmicro-footprints:Vishay_PowerPAK_1212-8_Single"
		(layer "F.Cu")
		(at 140.943001 116.399999)
		(descr "PowerPAK 1212-8 Single")
		(tags "Vishay PowerPAK 1212-8 Single")
		(property "Reference" "Q1"
			(at -3.543001 -0.799999 180)
			(layer "F.SilkS")
			(effects
				(font
					(size 0.7 0.7)
					(thickness 0.15)
				)
				(justify left bottom)
			)
		)
		(property "Value" "SQS401EN-T1_BE3"
			(at 0 2.7 0)
			(layer "F.Fab")
			(effects
				(font
					(size 0.7 0.7)
					(thickness 0.15)
				)
				(justify left bottom)
			)
		)
		(property "Datasheet" "https://www.vishay.com/docs/65529/sqs401en.pdf"
			(at 0 0 0)
			(layer "F.Fab")
			(hide yes)
			(effects
				(font
					(size 1.27 1.27)
					(thickness 0.15)
				)
			)
		)
		(property "Description" "MOSFET, P Channel, 40 V, 16A, 0.047 ohm, PowerPAK 1212-8, Surface Mount"
			(at 0 0 0)
			(layer "F.Fab")
			(hide yes)
			(effects
				(font
					(size 1.27 1.27)
					(thickness 0.15)
				)
			)
		)
		(property "MPN" "SQS401EN-T1_BE3"
			(at 0 0 0)
			(unlocked yes)
			(layer "F.Fab")
			(hide yes)
			(effects
				(font
					(size 1 1)
					(thickness 0.15)
				)
			)
		)
		(property "Manufacturer" "Vishay"
			(at 0 0 0)
			(unlocked yes)
			(layer "F.Fab")
			(hide yes)
			(effects
				(font
					(size 1 1)
					(thickness 0.15)
				)
			)
		)
		(property "Author" "Antmicro"
			(at 0 0 0)
			(unlocked yes)
			(layer "F.Fab")
			(hide yes)
			(effects
				(font
					(size 1 1)
					(thickness 0.15)
				)
			)
		)
		(property "License" "Apache-2.0"
			(at 0 0 0)
			(unlocked yes)
			(layer "F.Fab")
			(hide yes)
			(effects
				(font
					(size 1 1)
					(thickness 0.15)
				)
			)
		)
		(sheetname "/Power/Ideal-diode-1/")
		(sheetfile "ideal-diode.kicad_sch")
		(attr smd)
		(fp_line
			(start -1.651 -1.651)
			(end -1.651 -1.317)
			(stroke
				(width 0.15)
				(type solid)
			)
			(layer "F.SilkS")
		)
		(fp_line
			(start -1.651 -1.651)
			(end 1.648 -1.651)
			(stroke
				(width 0.15)
				(type solid)
			)
			(layer "F.SilkS")
		)
		(fp_line
			(start -1.635 1.3)
			(end -1.635 1.634)
			(stroke
				(width 0.15)
				(type solid)
			)
			(layer "F.SilkS")
		)
		(fp_line
			(start -1.635 1.634)
			(end 1.634 1.634)
			(stroke
				(width 0.15)
				(type solid)
			)
			(layer "F.SilkS")
		)
		(fp_line
			(start 1.634 1.3)
			(end 1.634 1.634)
			(stroke
				(width 0.15)
				(type solid)
			)
			(layer "F.SilkS")
		)
		(fp_line
			(start 1.648 -1.651)
			(end 1.648 -1.317)
			(stroke
				(width 0.15)
				(type solid)
			)
			(layer "F.SilkS")
		)
		(fp_circle
			(center -1.9 -1.4)
			(end -1.85 -1.4)
			(stroke
				(width 0.15)
				(type solid)
			)
			(fill yes)
			(layer "F.SilkS")
		)
		(fp_rect
			(start -2 -1.8)
			(end 2 1.798)
			(stroke
				(width 0.05)
				(type solid)
			)
			(fill no)
			(layer "F.CrtYd")
		)
		(fp_line
			(start -1.6425 -1.4175)
			(end -1.4175 -1.6425)
			(stroke
				(width 0.15)
				(type solid)
			)
			(layer "F.Fab")
		)
		(fp_rect
			(start -1.651 -1.651)
			(end 1.648 1.648)
			(stroke
				(width 0.15)
				(type solid)
			)
			(fill no)
			(layer "F.Fab")
		)
		(fp_text user "${REFERENCE}"
			(at 0 -0.001 0)
			(layer "F.Fab")
			(effects
				(font
					(size 0.7 0.7)
					(thickness 0.15)
				)
				(justify left bottom)
			)
		)
		(fp_text user "License: Apache-2.0"
			(at -8 7.1 0)
			(layer "F.Fab")
			(effects
				(font
					(size 0.7 0.7)
					(thickness 0.15)
				)
				(justify left bottom)
			)
		)
		(fp_text user "Author: Antmicro"
			(at -8 5.9 0)
			(layer "F.Fab")
			(effects
				(font
					(size 0.7 0.7)
					(thickness 0.15)
				)
				(justify left bottom)
			)
		)
		(pad "1" smd rect
			(at -1.436 -0.99)
			(size 0.99 0.405)
			(layers "F.Cu" "F.Mask" "F.Paste")
			(net 87 "+12V")
			(pinfunction "S")
			(pintype "passive")
		)
		(pad "2" smd rect
			(at -1.436 -0.332)
			(size 0.99 0.405)
			(layers "F.Cu" "F.Mask" "F.Paste")
			(net 87 "+12V")
			(pinfunction "S")
			(pintype "passive")
		)
		(pad "3" smd rect
			(at -1.436 0.33)
			(size 0.99 0.405)
			(layers "F.Cu" "F.Mask" "F.Paste")
			(net 87 "+12V")
			(pinfunction "S")
			(pintype "passive")
		)
		(pad "4" smd rect
			(at -1.436 0.988)
			(size 0.99 0.405)
			(layers "F.Cu" "F.Mask" "F.Paste")
			(net 104 "Net-(Q1-G)")
			(pinfunction "G")
			(pintype "input")
		)
		(pad "5" smd custom
			(at 0.557 0)
			(size 1.725 2.235)
			(layers "F.Cu" "F.Mask" "F.Paste")
			(net 118 "/Power/Ideal-diode-1/VIN")
			(pinfunction "D")
			(pintype "passive")
			(zone_connect 2)
			(options
				(clearance outline)
				(anchor rect)
			)
			(primitives
				(gr_poly
					(pts
						(xy 0.8625 0.1275) (xy 0.8625 -0.1275) (xy 1.3725 -0.1275) (xy 1.3725 -0.5325) (xy 0.8625 -0.5325)
						(xy 0.8625 -0.7875) (xy 1.3725 -0.7875) (xy 1.3725 -1.195) (xy 0.6125 -1.195) (xy 0.6125 1.195)
						(xy 1.3725 1.195) (xy 1.3725 0.7875) (xy 0.8625 0.7875) (xy 0.8625 0.5325) (xy 1.3725 0.5325)
						(xy 1.3725 0.1275)
					)
					(width 0)
					(fill yes)
				)
			)
		)
	)
)
